G04 ================== begin FILE IDENTIFICATION RECORD ==================*
G04 Layout Name:  F:/<user>/2022/FB/R4006-TIMING/brd/gerber-3/R4006-B0001-02_R01.brd*
G04 Film Name:    R4006-B0001-02_R01_OTL*
G04 File Format:  Gerber RS274X*
G04 File Origin:  Cadence Allegro 17.2-S079*
G04 Origin Date:  Fri Feb 25 18:14:44 2022*
G04 *
G04 Layer:  BOARD GEOMETRY/OUTLINE*
G04 *
G04 Offset:    (0.00 0.00)*
G04 Mirror:    No*
G04 Mode:      Positive*
G04 Rotation:  0*
G04 FullContactRelief:  No*
G04 UndefLineWidth:     6.00*
G04 ================== end FILE IDENTIFICATION RECORD ====================*
%FSLAX55Y55*MOIN*%
%IR0*IPPOS*OFA0.00000B0.00000*MIA0B0*SFA1.00000B1.00000*%
%ADD10C,.006*%
G75*
%LPD*%
G75*
G54D10*
G01X658071Y284646D02*
G03X660039Y286614I0J1968D01*
G01Y433661D01*
G03X656102Y437598I-3937J0D01*
G01X3937D01*
G03X0Y433661I0J-3937D01*
G01Y21654D01*
G03X3937Y17717I3937J0D01*
G01X55118D01*
G03X59055Y21654I0J3937D01*
G01Y46260D01*
G02X62992Y50197I3937J0D01*
G01X127362D01*
G02X131299Y46260I0J-3937D01*
G01Y21654D01*
G03X135236Y17717I3937J0D01*
G01X158858D01*
G03X162795Y21654I0J3937D01*
G01Y43012D01*
G02X177165I7185J0D01*
G01Y1969D01*
X179134Y0D01*
X219291D01*
X221260Y1969D01*
Y29331D01*
G02X228740I3740J0D01*
G01Y1969D01*
X230709Y0D01*
X310236D01*
X312205Y1969D01*
Y46260D01*
G02X316142Y50197I3937J0D01*
G01X656102D01*
G03X660039Y54134I0J3937D01*
G01Y237500D01*
G03X658071Y239469I-1969J1D01*
G01X657211D01*
G02X655243Y241437I0J1968D01*
G01Y282677D01*
G02X657211Y284646I1968J0D01*
G01X658071D01*
M02*
